# S9S_MB_2U (Grand Teton) — schematic netlist excerpt (pin names and nets, part order shuffled) for the footprints in the layout excerpt that follows; sources: Cadence DE-HDL packaged netlist, KiCad conversion of 03242023_DA0F0TMBIJ0_F0T_Motherboard_J_brd_V01_OCP.brd

PC1267  Q_CAP  0.1UF 25V 10% X7R  pkg 0402  page 299 : A = PVPP_HBM_CPU1 ; B = GND

Q74  MOSFET_NCH_DUAL  PJT138K IC  pkg SOT363XD  page 148
  S1  = GND
  G1  = FM_SMB_2_ALERT_GPU_N
  D2  = FM_SMB_2_ALERT_GPU_ISO_N
  S2  = GND
  G2  = FM_SMB_2_ALERT_GPU
  D1  = FM_SMB_2_ALERT_GPU

(kicad_pcb
	(version 20260206)
	(generator "pcbnew")
	(generator_version "10.0")
	(general
		(thickness 1.6)
		(legacy_teardrops no)
	)
	(paper "A4")
	(title_block
		(title "03242023_DA0F0TMBIJ0_F0T_Motherboard_J_brd_V01_OCP.brd")
		(comment 1 "Grand Teton / footprints 3714-3715 of 6105")
	)
	(layers
		(0 "F.Cu" signal "TOP")
		(4 "In1.Cu" signal "GND")
		(6 "In2.Cu" signal "IN1")
		(8 "In3.Cu" signal "GND1")
		(10 "In4.Cu" signal "IN2")
		(12 "In5.Cu" signal "GND2")
		(14 "In6.Cu" signal "IN3")
		(16 "In7.Cu" signal "GND3")
		(18 "In8.Cu" signal "VCC")
		(20 "In9.Cu" signal "VCC1")
		(22 "In10.Cu" signal "GND4")
		(24 "In11.Cu" signal "IN4")
		(26 "In12.Cu" signal "GND5")
		(28 "In13.Cu" signal "IN5")
		(30 "In14.Cu" signal "GND6")
		(32 "In15.Cu" signal "IN6")
		(34 "In16.Cu" signal "GND7")
		(2 "B.Cu" signal "BOTTOM")
		(9 "F.Adhes" user "F.Adhesive")
		(11 "B.Adhes" user "B.Adhesive")
		(13 "F.Paste" user "Package Geometry/Pastemask Top")
		(15 "B.Paste" user "Package Geometry/Pastemask Bottom")
		(5 "F.SilkS" user "Ref Des/Silkscreen Top")
		(7 "B.SilkS" user "Ref Des/Silkscreen Bottom")
		(1 "F.Mask" user "Board Geometry/Soldermask Top")
		(3 "B.Mask" user "Board Geometry/Soldermask Bottom")
		(17 "Dwgs.User" user "User.Drawings")
		(19 "Cmts.User" user "User.Comments")
		(21 "Eco1.User" user "User.Eco1")
		(23 "Eco2.User" user "User.Eco2")
		(25 "Edge.Cuts" user "Board Geometry/Outline")
		(27 "Margin" user)
		(31 "F.CrtYd" user "Package Geometry/Place Bound Top")
		(29 "B.CrtYd" user "Package Geometry/Place Bound Bottom")
		(35 "F.Fab" user "Ref Des/Assembly Top")
		(33 "B.Fab" user "Ref Des/Assembly Bottom")
	)
	(footprint ""
		(layer "F.Cu")
		(at 113.16208 -395.207998 -90)
		(property "Reference" "Q74"
			(at 0.98806 -4.43484 0)
			(unlocked yes)
			(layer "F.SilkS")
			(effects
				(font
					(size 0.7874 0.5842)
					(thickness 0.1524)
				)
				(justify left)
			)
		)
		(property "Value" ""
			(at 0 0 270)
			(layer "F.Fab")
			(effects
				(font
					(size 1.27 1.27)
				)
			)
		)
		(duplicate_pad_numbers_are_jumpers no)
		(fp_line
			(start -1.332738 1.100074)
			(end -1.332738 -1.100074)
			(stroke
				(width 0.1524)
				(type default)
			)
			(layer "F.SilkS")
		)
		(fp_line
			(start 1.332738 1.100074)
			(end -1.332738 1.100074)
			(stroke
				(width 0.1524)
				(type default)
			)
			(layer "F.SilkS")
		)
		(fp_line
			(start 0 -0.541274)
			(end 0.4826 -1.100074)
			(stroke
				(width 0.1524)
				(type default)
			)
			(layer "F.SilkS")
		)
		(fp_line
			(start -1.332738 -1.100074)
			(end -0.4826 -1.100074)
			(stroke
				(width 0.1524)
				(type default)
			)
			(layer "F.SilkS")
		)
		(fp_line
			(start -0.4826 -1.100074)
			(end 0 -0.541274)
			(stroke
				(width 0.1524)
				(type default)
			)
			(layer "F.SilkS")
		)
		(fp_line
			(start 0.4826 -1.100074)
			(end 1.332738 -1.100074)
			(stroke
				(width 0.1524)
				(type default)
			)
			(layer "F.SilkS")
		)
		(fp_line
			(start 1.332738 -1.100074)
			(end 1.332738 1.100074)
			(stroke
				(width 0.1524)
				(type default)
			)
			(layer "F.SilkS")
		)
		(fp_poly
			(pts
				(xy -0.661416 -2.06121) (xy -1.012444 -1.359154) (xy -1.363472 -2.06121)
			)
			(stroke
				(width 0)
				(type default)
			)
			(fill yes)
			(layer "F.SilkS")
		)
		(fp_line
			(start -0.674878 1.100074)
			(end -0.674878 -1.100074)
			(stroke
				(width 0.1)
				(type default)
			)
			(layer "F.Fab")
		)
		(fp_line
			(start 0.674878 1.100074)
			(end -0.674878 1.100074)
			(stroke
				(width 0.1)
				(type default)
			)
			(layer "F.Fab")
		)
		(fp_line
			(start -0.674878 -1.100074)
			(end 0.674878 -1.100074)
			(stroke
				(width 0.1)
				(type default)
			)
			(layer "F.Fab")
		)
		(fp_line
			(start 0.674878 -1.100074)
			(end 0.674878 1.100074)
			(stroke
				(width 0.1)
				(type default)
			)
			(layer "F.Fab")
		)
		(fp_poly
			(pts
				(xy -2.2352 -0.298958) (xy -2.2352 -1.001014) (xy -1.533144 -0.649986)
			)
			(stroke
				(width 0)
				(type default)
			)
			(fill yes)
			(layer "F.Fab")
		)
		(pad "1" smd rect
			(at -0.94996 -0.649986)
			(size 0.4318 0.508)
			(layers "F.Cu" "F.Mask" "F.Paste")
			(net "GND")
		)
		(pad "2" smd rect
			(at -0.94996 0)
			(size 0.4318 0.508)
			(layers "F.Cu" "F.Mask" "F.Paste")
			(net "FM_SMB_2_ALERT_GPU_N")
		)
		(pad "3" smd rect
			(at -0.94996 0.649986)
			(size 0.4318 0.508)
			(layers "F.Cu" "F.Mask" "F.Paste")
			(net "FM_SMB_2_ALERT_GPU_ISO_N")
		)
		(pad "4" smd rect
			(at 0.94996 0.649986)
			(size 0.4318 0.508)
			(layers "F.Cu" "F.Mask" "F.Paste")
			(net "GND")
		)
		(pad "5" smd rect
			(at 0.94996 0)
			(size 0.4318 0.508)
			(layers "F.Cu" "F.Mask" "F.Paste")
			(net "FM_SMB_2_ALERT_GPU")
		)
		(pad "6" smd rect
			(at 0.94996 -0.649986)
			(size 0.4318 0.508)
			(layers "F.Cu" "F.Mask" "F.Paste")
			(net "FM_SMB_2_ALERT_GPU")
		)
	)
	(footprint ""
		(layer "F.Cu")
		(at 121.52884 -366.796066 -90)
		(property "Reference" "PC1267"
			(at 0 0 270)
			(layer "F.SilkS")
			(hide yes)
			(effects
				(font
					(size 1.27 1.27)
				)
			)
		)
		(property "Value" ""
			(at 0 0 270)
			(layer "F.Fab")
			(effects
				(font
					(size 1.27 1.27)
				)
			)
		)
		(duplicate_pad_numbers_are_jumpers no)
		(fp_line
			(start -0.7874 0.4064)
			(end -0.7874 -0.4064)
			(stroke
				(width 0.1524)
				(type default)
			)
			(layer "F.SilkS")
		)
		(fp_line
			(start 0.7874 0.4064)
			(end -0.7874 0.4064)
			(stroke
				(width 0.1524)
				(type default)
			)
			(layer "F.SilkS")
		)
		(fp_line
			(start -0.7874 -0.4064)
			(end 0.7874 -0.4064)
			(stroke
				(width 0.1524)
				(type default)
			)
			(layer "F.SilkS")
		)
		(fp_line
			(start 0.7874 -0.4064)
			(end 0.7874 0.4064)
			(stroke
				(width 0.1524)
				(type default)
			)
			(layer "F.SilkS")
		)
		(fp_line
			(start -0.67945 0.3048)
			(end -0.67945 -0.305054)
			(stroke
				(width 0.1)
				(type default)
			)
			(layer "F.Fab")
		)
		(fp_line
			(start -0.12065 0.3048)
			(end -0.67945 0.3048)
			(stroke
				(width 0.1)
				(type default)
			)
			(layer "F.Fab")
		)
		(fp_line
			(start 0.120396 0.3048)
			(end 0.120396 0.2794)
			(stroke
				(width 0.1)
				(type default)
			)
			(layer "F.Fab")
		)
		(fp_line
			(start 0.67945 0.3048)
			(end 0.120396 0.3048)
			(stroke
				(width 0.1)
				(type default)
			)
			(layer "F.Fab")
		)
		(fp_line
			(start -0.12065 0.2794)
			(end -0.12065 0.3048)
			(stroke
				(width 0.1)
				(type default)
			)
			(layer "F.Fab")
		)
		(fp_line
			(start 0.120396 0.2794)
			(end -0.12065 0.2794)
			(stroke
				(width 0.1)
				(type default)
			)
			(layer "F.Fab")
		)
		(fp_line
			(start -0.12065 -0.2794)
			(end 0.12065 -0.2794)
			(stroke
				(width 0.1)
				(type default)
			)
			(layer "F.Fab")
		)
		(fp_line
			(start 0.12065 -0.2794)
			(end 0.12065 -0.3048)
			(stroke
				(width 0.1)
				(type default)
			)
			(layer "F.Fab")
		)
		(fp_line
			(start 0.12065 -0.3048)
			(end 0.67945 -0.3048)
			(stroke
				(width 0.1)
				(type default)
			)
			(layer "F.Fab")
		)
		(fp_line
			(start 0.67945 -0.3048)
			(end 0.67945 0.3048)
			(stroke
				(width 0.1)
				(type default)
			)
			(layer "F.Fab")
		)
		(fp_line
			(start -0.67945 -0.305054)
			(end -0.12065 -0.305054)
			(stroke
				(width 0.1)
				(type default)
			)
			(layer "F.Fab")
		)
		(fp_line
			(start -0.12065 -0.305054)
			(end -0.12065 -0.2794)
			(stroke
				(width 0.1)
				(type default)
			)
			(layer "F.Fab")
		)
		(pad "1" smd circle
			(at -0.40005 0 270)
			(size 0 0)
			(layers "F.Cu" "F.Mask" "F.Paste")
			(net "PVPP_HBM_CPU1")
		)
		(pad "2" smd circle
			(at 0.40005 0 270)
			(size 0 0)
			(layers "F.Cu" "F.Mask" "F.Paste")
			(net "GND")
		)
	)
)
